#ISCELL
  mstr_misc prelim *
  *
#ISCELL
  mstr_symbols design_note *
  *
#ISCELL
  mstr_symbols intel_corp_bpage *
  *
#ISCELL
  mstr_standard tap *
  page29_i10
#ISCELL
  mstr_standard tap *
  page29_i11
#ISCELL
  mstr_standard tap *
  page29_i12
#ISCELL
  mstr_standard tap *
  page29_i13
#ISCELL
  mstr_standard tap *
  page29_i14
#ISCELL
  mstr_standard tap *
  page29_i16
#ISCELL
  mstr_standard tap *
  page29_i17
#ISCELL
  mstr_standard tap *
  page29_i18
#ISCELL
  mstr_standard tap *
  page29_i19
#ISCELL
  mstr_standard tap *
  page29_i20
#ISCELL
  mstr_standard tap *
  page29_i21
#ISCELL
  mstr_standard tap *
  page29_i22
#ISCELL
  mstr_standard tap *
  page29_i23
#ISCELL
  mstr_standard offpage *
  page29_i25
#ISCELL
  mstr_standard offpage *
  page29_i26
#ISCELL
  mstr_standard offpage *
  page29_i27
#ISCELL
  mstr_standard offpage *
  page29_i28
#ISCELL
  mstr_standard offpage *
  page29_i29
#ISCELL
  mstr_standard offpage *
  page29_i31
#ISCELL
  mstr_standard offpage *
  page29_i35
#ISCELL
  mstr_standard offpage *
  page29_i36
#ISCELL
  mstr_standard offpage *
  page29_i40
#ISCELL
  mstr_standard offpage *
  page29_i41
#ISCELL
  mstr_standard offpage *
  page29_i42
#ISCELL
  mstr_standard offpage *
  page29_i43
#ISCELL
  mstr_standard offpage *
  page29_i44
#ISCELL
  mstr_standard offpage *
  page29_i45
#ISCELL
  mstr_standard offpage *
  page29_i46
#ISCELL
  mstr_standard offpage *
  page29_i47
#ISCELL
  mstr_standard offpage *
  page29_i48
#ISCELL
  mstr_standard offpage *
  page29_i49
#ISCELL
  mstr_standard offpage *
  page29_i5
#ISCELL
  mstr_standard offpage *
  page29_i50
#ISCELL
  mstr_standard offpage *
  page29_i51
#ISCELL
  mstr_standard offpage *
  page29_i52
#ISCELL
  mstr_standard offpage *
  page29_i53
#ISCELL
  mstr_standard offpage *
  page29_i54
#ISCELL
  mstr_standard offpage *
  page29_i58
#ISCELL
  mstr_standard offpage *
  page29_i6
#ISCELL
  mstr_symbols vcc_core *
  page29_i60
#CELL
  chpset_lib skx_ext_b *
  page29_i61
#ISCELL
  mstr_standard tap *
  page29_i7
#ISCELL
  mstr_standard tap *
  page29_i8
#ISCELL
  mstr_standard tap *
  page29_i9
